# T6G (Grand Teton) — schematic netlist excerpt (pin names and nets, part order shuffled) for the footprints in the layout excerpt that follows; sources: Cadence DE-HDL packaged netlist, KiCad conversion of 04192023_DAF0TMB3IC0_F0TG_MB_C_brd_V02_OCP.brd

PC136_5  Q_CAP  22UF 16V 20% X6S  pkg C0805  page 203 : A = SW_P12V_AUX_PVDDCR_CPU1_P0_FLT ; B = GND
C279  Q_CAP  22UF 4V 20% X6S  pkg C0402  page 69 : A = PVDDCR_CPU0_P0 ; B = GND
R806  Q_RES  0 5% CHIP  pkg 0201LF  page 185 : A = SMB_RT_CPU1_P3_ROM_MUX_2D_SDA ; B = SMB_RT_CPU1_P3_ROM_MUX_2D_R_SDA

(kicad_pcb
	(version 20260206)
	(generator "pcbnew")
	(generator_version "10.0")
	(general
		(thickness 1.6)
		(legacy_teardrops no)
	)
	(paper "A4")
	(title_block
		(title "04192023_DAF0TMB3IC0_F0TG_MB_C_brd_V02_OCP.brd")
		(comment 1 "Grand Teton / footprints 7281-7283 of 8354")
	)
	(layers
		(0 "F.Cu" signal "TOP")
		(4 "In1.Cu" signal "GND")
		(6 "In2.Cu" signal "IN1")
		(8 "In3.Cu" signal "GND1")
		(10 "In4.Cu" signal "IN2")
		(12 "In5.Cu" signal "GND2")
		(14 "In6.Cu" signal "IN3")
		(16 "In7.Cu" signal "GND3")
		(18 "In8.Cu" signal "VCC")
		(20 "In9.Cu" signal "VCC1")
		(22 "In10.Cu" signal "GND4")
		(24 "In11.Cu" signal "IN4")
		(26 "In12.Cu" signal "GND5")
		(28 "In13.Cu" signal "IN5")
		(30 "In14.Cu" signal "GND6")
		(32 "In15.Cu" signal "IN6")
		(34 "In16.Cu" signal "GND7")
		(2 "B.Cu" signal "BOTTOM")
		(9 "F.Adhes" user "F.Adhesive")
		(11 "B.Adhes" user "B.Adhesive")
		(13 "F.Paste" user "Package Geometry/Pastemask Top")
		(15 "B.Paste" user "Package Geometry/Pastemask Bottom")
		(5 "F.SilkS" user "Ref Des/Silkscreen Top")
		(7 "B.SilkS" user "Ref Des/Silkscreen Bottom")
		(1 "F.Mask" user "Board Geometry/Soldermask Top")
		(3 "B.Mask" user "Board Geometry/Soldermask Bottom")
		(17 "Dwgs.User" user "User.Drawings")
		(19 "Cmts.User" user "User.Comments")
		(21 "Eco1.User" user "User.Eco1")
		(23 "Eco2.User" user "User.Eco2")
		(25 "Edge.Cuts" user "Board Geometry/Outline")
		(27 "Margin" user)
		(31 "F.CrtYd" user "Package Geometry/Place Bound Top")
		(29 "B.CrtYd" user "Package Geometry/Place Bound Bottom")
		(35 "F.Fab" user "Ref Des/Assembly Top")
		(33 "B.Fab" user "Ref Des/Assembly Bottom")
	)
	(footprint ""
		(layer "B.Cu")
		(at 357.835454 -250.25731)
		(property "Reference" "C279"
			(at 0 0 0)
			(layer "B.SilkS")
			(hide yes)
			(effects
				(font
					(size 1.27 1.27)
				)
				(justify mirror)
			)
		)
		(property "Value" ""
			(at 0 0 0)
			(layer "B.Fab")
			(effects
				(font
					(size 1.27 1.27)
				)
				(justify mirror)
			)
		)
		(duplicate_pad_numbers_are_jumpers no)
		(fp_line
			(start -0.7874 -0.4064)
			(end -0.7874 0.4064)
			(stroke
				(width 0.1524)
				(type default)
			)
			(layer "B.SilkS")
		)
		(fp_line
			(start -0.7874 0.4064)
			(end 0.7874 0.4064)
			(stroke
				(width 0.1524)
				(type default)
			)
			(layer "B.SilkS")
		)
		(fp_line
			(start 0.7874 -0.4064)
			(end -0.7874 -0.4064)
			(stroke
				(width 0.1524)
				(type default)
			)
			(layer "B.SilkS")
		)
		(fp_line
			(start 0.7874 0.4064)
			(end 0.7874 -0.4064)
			(stroke
				(width 0.1524)
				(type default)
			)
			(layer "B.SilkS")
		)
		(fp_line
			(start -0.67945 -0.3048)
			(end -0.67945 0.3048)
			(stroke
				(width 0.1)
				(type default)
			)
			(layer "B.Fab")
		)
		(fp_line
			(start -0.67945 0.3048)
			(end -0.120396 0.3048)
			(stroke
				(width 0.1)
				(type default)
			)
			(layer "B.Fab")
		)
		(fp_line
			(start -0.12065 -0.3048)
			(end -0.67945 -0.3048)
			(stroke
				(width 0.1)
				(type default)
			)
			(layer "B.Fab")
		)
		(fp_line
			(start -0.12065 -0.2794)
			(end -0.12065 -0.3048)
			(stroke
				(width 0.1)
				(type default)
			)
			(layer "B.Fab")
		)
		(fp_line
			(start -0.120396 0.2794)
			(end 0.12065 0.2794)
			(stroke
				(width 0.1)
				(type default)
			)
			(layer "B.Fab")
		)
		(fp_line
			(start -0.120396 0.3048)
			(end -0.120396 0.2794)
			(stroke
				(width 0.1)
				(type default)
			)
			(layer "B.Fab")
		)
		(fp_line
			(start 0.12065 -0.305054)
			(end 0.12065 -0.2794)
			(stroke
				(width 0.1)
				(type default)
			)
			(layer "B.Fab")
		)
		(fp_line
			(start 0.12065 -0.2794)
			(end -0.12065 -0.2794)
			(stroke
				(width 0.1)
				(type default)
			)
			(layer "B.Fab")
		)
		(fp_line
			(start 0.12065 0.2794)
			(end 0.12065 0.3048)
			(stroke
				(width 0.1)
				(type default)
			)
			(layer "B.Fab")
		)
		(fp_line
			(start 0.12065 0.3048)
			(end 0.67945 0.3048)
			(stroke
				(width 0.1)
				(type default)
			)
			(layer "B.Fab")
		)
		(fp_line
			(start 0.67945 -0.305054)
			(end 0.12065 -0.305054)
			(stroke
				(width 0.1)
				(type default)
			)
			(layer "B.Fab")
		)
		(fp_line
			(start 0.67945 0.3048)
			(end 0.67945 -0.305054)
			(stroke
				(width 0.1)
				(type default)
			)
			(layer "B.Fab")
		)
		(pad "1" smd circle
			(at 0.40005 0 180)
			(size 0 0)
			(layers "B.Cu" "B.Mask" "B.Paste")
			(net "PVDDCR_CPU0_P0")
		)
		(pad "2" smd circle
			(at -0.40005 0 180)
			(size 0 0)
			(layers "B.Cu" "B.Mask" "B.Paste")
			(net "GND")
		)
	)
	(footprint ""
		(layer "B.Cu")
		(at 238.633 -338.455 180)
		(property "Reference" "R806"
			(at 0 0 0)
			(layer "B.SilkS")
			(hide yes)
			(effects
				(font
					(size 1.27 1.27)
				)
				(justify mirror)
			)
		)
		(property "Value" ""
			(at 0 0 0)
			(layer "B.Fab")
			(effects
				(font
					(size 1.27 1.27)
				)
				(justify mirror)
			)
		)
		(duplicate_pad_numbers_are_jumpers no)
		(fp_line
			(start 0.32512 0.175006)
			(end 0.32512 -0.175006)
			(stroke
				(width 0.1)
				(type default)
			)
			(layer "B.Fab")
		)
		(fp_line
			(start 0.32512 -0.175006)
			(end -0.32512 -0.175006)
			(stroke
				(width 0.1)
				(type default)
			)
			(layer "B.Fab")
		)
		(fp_line
			(start -0.32512 0.175006)
			(end 0.32512 0.175006)
			(stroke
				(width 0.1)
				(type default)
			)
			(layer "B.Fab")
		)
		(fp_line
			(start -0.32512 -0.175006)
			(end -0.32512 0.175006)
			(stroke
				(width 0.1)
				(type default)
			)
			(layer "B.Fab")
		)
		(pad "1" smd rect
			(at 0.2667 0)
			(size 0.3048 0.381)
			(layers "B.Cu" "B.Mask" "B.Paste")
			(net "SMB_RT_CPU1_P3_ROM_MUX_2D_SDA")
		)
		(pad "2" smd rect
			(at -0.2667 0 180)
			(size 0.3048 0.381)
			(layers "B.Cu" "B.Mask" "B.Paste")
			(net "SMB_RT_CPU1_P3_ROM_MUX_2D_R_SDA")
		)
	)
	(footprint ""
		(layer "B.Cu")
		(at 344.511884 -338.964016 -90)
		(property "Reference" "PC136_5"
			(at 0 0 90)
			(layer "B.SilkS")
			(hide yes)
			(effects
				(font
					(size 1.27 1.27)
				)
				(justify mirror)
			)
		)
		(property "Value" ""
			(at 0 0 90)
			(layer "B.Fab")
			(effects
				(font
					(size 1.27 1.27)
				)
				(justify mirror)
			)
		)
		(duplicate_pad_numbers_are_jumpers no)
		(fp_line
			(start -1.524 0.762)
			(end 1.524 0.762)
			(stroke
				(width 0.1524)
				(type default)
			)
			(layer "B.SilkS")
		)
		(fp_line
			(start 1.524 0.762)
			(end 1.524 -0.762)
			(stroke
				(width 0.1524)
				(type default)
			)
			(layer "B.SilkS")
		)
		(fp_line
			(start -1.524 -0.762)
			(end -1.524 0.762)
			(stroke
				(width 0.1524)
				(type default)
			)
			(layer "B.SilkS")
		)
		(fp_line
			(start 1.524 -0.762)
			(end -1.524 -0.762)
			(stroke
				(width 0.1524)
				(type default)
			)
			(layer "B.SilkS")
		)
		(fp_line
			(start -1.1049 0.724916)
			(end -1.1049 -0.724916)
			(stroke
				(width 0.1)
				(type default)
			)
			(layer "B.Fab")
		)
		(fp_line
			(start 1.1049 0.724916)
			(end -1.1049 0.724916)
			(stroke
				(width 0.1)
				(type default)
			)
			(layer "B.Fab")
		)
		(fp_line
			(start -1.1049 -0.724916)
			(end 1.1049 -0.724916)
			(stroke
				(width 0.1)
				(type default)
			)
			(layer "B.Fab")
		)
		(fp_line
			(start 1.1049 -0.724916)
			(end 1.1049 0.724916)
			(stroke
				(width 0.1)
				(type default)
			)
			(layer "B.Fab")
		)
		(pad "1" smd rect
			(at 0.889 0 270)
			(size 1.016 1.27)
			(layers "B.Cu" "B.Mask" "B.Paste")
			(net "SW_P12V_AUX_PVDDCR_CPU1_P0_FLT")
		)
		(pad "2" smd rect
			(at -0.889 0 270)
			(size 1.016 1.27)
			(layers "B.Cu" "B.Mask" "B.Paste")
			(net "GND")
		)
	)
)
